# S9S_MB_2U (Grand Teton) — schematic netlist excerpt (pin names and nets, part order shuffled) for the footprints in the layout excerpt that follows; sources: Cadence DE-HDL packaged netlist, KiCad conversion of 03242023_DA0F0TMBIJ0_F0T_Motherboard_J_brd_V01_OCP.brd

C1566  Q_CAP_DIFFBUS  DIFF BUS_0.22UF 6.3V 20% X6S  pkg C0201  page 175 : \1\ = P5E_CPU0_PE4_TX_C_DN<6> ; \2\ = P5E_CPU0_PE4_TX_DN<6>
R1325  Q_RES  1K 1% CHIP  pkg 0402LF  page 201 : A = P3V3_AUX ; B = PU_FLASH_SECURITY_STRAP

(kicad_pcb
	(version 20260206)
	(generator "pcbnew")
	(generator_version "10.0")
	(general
		(thickness 1.6)
		(legacy_teardrops no)
	)
	(paper "A4")
	(title_block
		(title "03242023_DA0F0TMBIJ0_F0T_Motherboard_J_brd_V01_OCP.brd")
		(comment 1 "Grand Teton / footprints 1008-1009 of 6105")
	)
	(layers
		(0 "F.Cu" signal "TOP")
		(4 "In1.Cu" signal "GND")
		(6 "In2.Cu" signal "IN1")
		(8 "In3.Cu" signal "GND1")
		(10 "In4.Cu" signal "IN2")
		(12 "In5.Cu" signal "GND2")
		(14 "In6.Cu" signal "IN3")
		(16 "In7.Cu" signal "GND3")
		(18 "In8.Cu" signal "VCC")
		(20 "In9.Cu" signal "VCC1")
		(22 "In10.Cu" signal "GND4")
		(24 "In11.Cu" signal "IN4")
		(26 "In12.Cu" signal "GND5")
		(28 "In13.Cu" signal "IN5")
		(30 "In14.Cu" signal "GND6")
		(32 "In15.Cu" signal "IN6")
		(34 "In16.Cu" signal "GND7")
		(2 "B.Cu" signal "BOTTOM")
		(9 "F.Adhes" user "F.Adhesive")
		(11 "B.Adhes" user "B.Adhesive")
		(13 "F.Paste" user "Package Geometry/Pastemask Top")
		(15 "B.Paste" user "Package Geometry/Pastemask Bottom")
		(5 "F.SilkS" user "Ref Des/Silkscreen Top")
		(7 "B.SilkS" user "Ref Des/Silkscreen Bottom")
		(1 "F.Mask" user "Board Geometry/Soldermask Top")
		(3 "B.Mask" user "Board Geometry/Soldermask Bottom")
		(17 "Dwgs.User" user "User.Drawings")
		(19 "Cmts.User" user "User.Comments")
		(21 "Eco1.User" user "User.Eco1")
		(23 "Eco2.User" user "User.Eco2")
		(25 "Edge.Cuts" user "Board Geometry/Outline")
		(27 "Margin" user)
		(31 "F.CrtYd" user "Package Geometry/Place Bound Top")
		(29 "B.CrtYd" user "Package Geometry/Place Bound Bottom")
		(35 "F.Fab" user "Ref Des/Assembly Top")
		(33 "B.Fab" user "Ref Des/Assembly Bottom")
	)
	(footprint ""
		(layer "F.Cu")
		(at 413.520382 -32.925258)
		(property "Reference" "R1325"
			(at 0 0 0)
			(layer "F.SilkS")
			(hide yes)
			(effects
				(font
					(size 1.27 1.27)
				)
			)
		)
		(property "Value" ""
			(at 0 0 0)
			(layer "F.Fab")
			(effects
				(font
					(size 1.27 1.27)
				)
			)
		)
		(duplicate_pad_numbers_are_jumpers no)
		(fp_line
			(start -0.7874 -0.4064)
			(end 0.7874 -0.4064)
			(stroke
				(width 0.1524)
				(type default)
			)
			(layer "F.SilkS")
		)
		(fp_line
			(start -0.7874 0.4064)
			(end -0.7874 -0.4064)
			(stroke
				(width 0.1524)
				(type default)
			)
			(layer "F.SilkS")
		)
		(fp_line
			(start 0.7874 -0.4064)
			(end 0.7874 0.4064)
			(stroke
				(width 0.1524)
				(type default)
			)
			(layer "F.SilkS")
		)
		(fp_line
			(start 0.7874 0.4064)
			(end -0.7874 0.4064)
			(stroke
				(width 0.1524)
				(type default)
			)
			(layer "F.SilkS")
		)
		(fp_line
			(start -0.67945 -0.305054)
			(end -0.12065 -0.305054)
			(stroke
				(width 0.1)
				(type default)
			)
			(layer "F.Fab")
		)
		(fp_line
			(start -0.67945 0.3048)
			(end -0.67945 -0.305054)
			(stroke
				(width 0.1)
				(type default)
			)
			(layer "F.Fab")
		)
		(fp_line
			(start -0.12065 -0.305054)
			(end -0.12065 -0.2794)
			(stroke
				(width 0.1)
				(type default)
			)
			(layer "F.Fab")
		)
		(fp_line
			(start -0.12065 -0.2794)
			(end 0.12065 -0.2794)
			(stroke
				(width 0.1)
				(type default)
			)
			(layer "F.Fab")
		)
		(fp_line
			(start -0.12065 0.2794)
			(end -0.12065 0.3048)
			(stroke
				(width 0.1)
				(type default)
			)
			(layer "F.Fab")
		)
		(fp_line
			(start -0.12065 0.3048)
			(end -0.67945 0.3048)
			(stroke
				(width 0.1)
				(type default)
			)
			(layer "F.Fab")
		)
		(fp_line
			(start 0.120396 0.2794)
			(end -0.12065 0.2794)
			(stroke
				(width 0.1)
				(type default)
			)
			(layer "F.Fab")
		)
		(fp_line
			(start 0.120396 0.3048)
			(end 0.120396 0.2794)
			(stroke
				(width 0.1)
				(type default)
			)
			(layer "F.Fab")
		)
		(fp_line
			(start 0.12065 -0.3048)
			(end 0.67945 -0.3048)
			(stroke
				(width 0.1)
				(type default)
			)
			(layer "F.Fab")
		)
		(fp_line
			(start 0.12065 -0.2794)
			(end 0.12065 -0.3048)
			(stroke
				(width 0.1)
				(type default)
			)
			(layer "F.Fab")
		)
		(fp_line
			(start 0.67945 -0.3048)
			(end 0.67945 0.3048)
			(stroke
				(width 0.1)
				(type default)
			)
			(layer "F.Fab")
		)
		(fp_line
			(start 0.67945 0.3048)
			(end 0.120396 0.3048)
			(stroke
				(width 0.1)
				(type default)
			)
			(layer "F.Fab")
		)
		(pad "1" smd circle
			(at -0.40005 0)
			(size 0 0)
			(layers "F.Cu" "F.Mask" "F.Paste")
			(net "P3V3_AUX")
		)
		(pad "2" smd circle
			(at 0.40005 0)
			(size 0 0)
			(layers "F.Cu" "F.Mask" "F.Paste")
			(net "PU_FLASH_SECURITY_STRAP")
		)
	)
	(footprint ""
		(layer "F.Cu")
		(at 322.334128 -402.371052 -90)
		(property "Reference" "C1566"
			(at 0 0 270)
			(layer "F.SilkS")
			(hide yes)
			(effects
				(font
					(size 1.27 1.27)
				)
			)
		)
		(property "Value" ""
			(at 0 0 270)
			(layer "F.Fab")
			(effects
				(font
					(size 1.27 1.27)
				)
			)
		)
		(duplicate_pad_numbers_are_jumpers no)
		(fp_line
			(start -0.299974 0.150114)
			(end -0.299974 -0.150114)
			(stroke
				(width 0.1)
				(type default)
			)
			(layer "F.Fab")
		)
		(fp_line
			(start 0.299974 0.150114)
			(end -0.299974 0.150114)
			(stroke
				(width 0.1)
				(type default)
			)
			(layer "F.Fab")
		)
		(fp_line
			(start -0.299974 -0.150114)
			(end 0.299974 -0.150114)
			(stroke
				(width 0.1)
				(type default)
			)
			(layer "F.Fab")
		)
		(fp_line
			(start 0.299974 -0.150114)
			(end 0.299974 0.150114)
			(stroke
				(width 0.1)
				(type default)
			)
			(layer "F.Fab")
		)
		(pad "1" smd rect
			(at -0.2667 0 270)
			(size 0.3048 0.381)
			(layers "F.Cu" "F.Mask" "F.Paste")
			(net "P5E_CPU0_PE4_TX_C_DN<6>")
		)
		(pad "2" smd rect
			(at 0.2667 0 270)
			(size 0.3048 0.381)
			(layers "F.Cu" "F.Mask" "F.Paste")
			(net "P5E_CPU0_PE4_TX_DN<6>")
		)
	)
)
